#ISCELL
  pure_quanta quanta_title_block_c *
  *
#ISCELL
  pure_quanta_power universal_gnd *
  page265_i1
#ISCELL
  pure_quanta_power universal_gnd *
  page265_i10
#ISCELL
  pure_quanta_power universal_gnd *
  page265_i11
#CELL
  pure_quanta tdr_3p *
  page265_i12
#CELL
  pure_quanta tdr_3p *
  page265_i13
#ISCELL
  pure_quanta_power universal_gnd *
  page265_i14
#CELL
  pure_quanta tdr_3p *
  page265_i15
#CELL
  pure_quanta tdr_3p *
  page265_i16
#ISCELL
  pure_quanta_power universal_gnd *
  page265_i17
#CELL
  pure_quanta tdr_3p *
  page265_i18
#ISCELL
  pure_quanta_power universal_gnd *
  page265_i19
#CELL
  pure_quanta tdr_3p *
  page265_i2
#CELL
  pure_quanta tdr_3p *
  page265_i20
#ISCELL
  pure_quanta_power universal_gnd *
  page265_i21
#CELL
  pure_quanta tdr_3p *
  page265_i22
#ISCELL
  pure_quanta_power universal_gnd *
  page265_i23
#ISCELL
  pure_quanta_power universal_gnd *
  page265_i24
#CELL
  pure_quanta tdr_3p *
  page265_i25
#ISCELL
  pure_quanta_power universal_gnd *
  page265_i26
#ISCELL
  pure_quanta_power universal_gnd *
  page265_i27
#ISCELL
  pure_quanta_power universal_gnd *
  page265_i28
#CELL
  pure_quanta tp_tdr_4p_fts *
  page265_i29
#ISCELL
  pure_quanta_power universal_gnd *
  page265_i3
#CELL
  pure_quanta tp_tdr_4p_fts *
  page265_i30
#CELL
  pure_quanta tp_tdr_4p_fts *
  page265_i31
#ISCELL
  pure_quanta_power universal_gnd *
  page265_i32
#ISCELL
  pure_quanta_power universal_gnd *
  page265_i33
#ISCELL
  pure_quanta_power universal_gnd *
  page265_i34
#CELL
  pure_quanta tp_tdr_4p_fts *
  page265_i35
#CELL
  pure_quanta tp_tdr_4p_fts *
  page265_i36
#CELL
  pure_quanta tp_tdr_4p_fts *
  page265_i37
#CELL
  pure_quanta tdr_3p *
  page265_i38
#ISCELL
  pure_quanta_power universal_gnd *
  page265_i39
#ISCELL
  pure_quanta_power universal_gnd *
  page265_i4
#CELL
  pure_quanta tdr_3p *
  page265_i40
#ISCELL
  pure_quanta_power universal_gnd *
  page265_i41
#CELL
  pure_quanta tdr_3p *
  page265_i42
#ISCELL
  pure_quanta_power universal_gnd *
  page265_i43
#CELL
  pure_quanta tdr_3p *
  page265_i44
#ISCELL
  pure_quanta_power universal_gnd *
  page265_i45
#ISCELL
  pure_quanta_power universal_gnd *
  page265_i46
#CELL
  pure_quanta tp_tdr_4p_fts *
  page265_i47
#CELL
  pure_quanta tp_tdr_4p_fts *
  page265_i48
#CELL
  pure_quanta tp_tdr_4p_fts *
  page265_i49
#CELL
  pure_quanta tdr_3p *
  page265_i5
#ISCELL
  pure_quanta_power universal_gnd *
  page265_i50
#ISCELL
  pure_quanta_power universal_gnd *
  page265_i51
#CELL
  pure_quanta tp_tdr_4p_fts *
  page265_i52
#CELL
  pure_quanta tp_tdr_4p_fts *
  page265_i53
#ISCELL
  pure_quanta_power universal_gnd *
  page265_i54
#ISCELL
  pure_quanta_power universal_gnd *
  page265_i55
#CELL
  pure_quanta tp_tdr_4p_fts *
  page265_i56
#ISCELL
  pure_quanta_power universal_gnd *
  page265_i57
#CELL
  pure_quanta tp_tdr_4p_fts *
  page265_i58
#ISCELL
  pure_quanta_power universal_gnd *
  page265_i59
#ISCELL
  pure_quanta_power universal_gnd *
  page265_i6
#CELL
  pure_quanta tp_tdr_4p_fts *
  page265_i60
#CELL
  pure_quanta tp_tdr_4p_fts *
  page265_i61
#CELL
  pure_quanta tp_tdr_4p_fts *
  page265_i62
#ISCELL
  pure_quanta_power universal_gnd *
  page265_i63
#ISCELL
  pure_quanta_power universal_gnd *
  page265_i64
#ISCELL
  pure_quanta_power universal_gnd *
  page265_i65
#CELL
  pure_quanta tp_tdr_4p_fts *
  page265_i66
#ISCELL
  pure_quanta_power universal_gnd *
  page265_i67
#CELL
  pure_quanta tp_tdr_4p_fts *
  page265_i68
#ISCELL
  pure_quanta_power universal_gnd *
  page265_i69
#ISCELL
  pure_quanta_power universal_gnd *
  page265_i7
#CELL
  pure_quanta tp_tdr_4p_fts *
  page265_i70
#ISCELL
  pure_quanta_power universal_gnd *
  page265_i71
#ISCELL
  pure_quanta_power universal_gnd *
  page265_i72
#CELL
  pure_quanta tp_tdr_4p_fts *
  page265_i73
#CELL
  pure_quanta tp_tdr_4p_fts *
  page265_i74
#ISCELL
  pure_quanta_power universal_gnd *
  page265_i75
#CELL
  pure_quanta tp_tdr_4p_fts *
  page265_i76
#ISCELL
  pure_quanta_power universal_gnd *
  page265_i77
#CELL
  pure_quanta tp_tdr_4p_fts *
  page265_i78
#CELL
  pure_quanta tp_tdr_4p_fts *
  page265_i79
#CELL
  pure_quanta tdr_3p *
  page265_i8
#ISCELL
  pure_quanta_power universal_gnd *
  page265_i80
#ISCELL
  pure_quanta_power universal_gnd *
  page265_i81
#CELL
  pure_quanta tp_tdr_4p_fts *
  page265_i82
#ISCELL
  pure_quanta_power universal_gnd *
  page265_i83
#CELL
  pure_quanta tp_tdr_4p_fts *
  page265_i84
#ISCELL
  pure_quanta_power universal_gnd *
  page265_i85
#ISCELL
  pure_quanta_power universal_gnd *
  page265_i86
#CELL
  pure_quanta tp_tdr_4p_fts *
  page265_i87
#ISCELL
  pure_quanta_power universal_gnd *
  page265_i88
#CELL
  pure_quanta tp_tdr_4p_fts *
  page265_i89
#CELL
  pure_quanta tdr_3p *
  page265_i9
#CELL
  pure_quanta tp_tdr_4p_fts *
  page265_i90
#ISCELL
  pure_quanta_power universal_gnd *
  page265_i91
#CELL
  pure_quanta tp_tdr_4p_fts *
  page265_i92
#ISCELL
  pure_quanta_power universal_gnd *
  page265_i93
#CELL
  pure_quanta tp_tdr_4p_fts *
  page265_i94
#ISCELL
  pure_quanta_power universal_gnd *
  page265_i95
#CELL
  pure_quanta tp_tdr_4p_fts *
  page265_i96
